# BASEBOARD_FAB2 (Tioga Pass) — schematic netlist excerpt (pin names and nets, part order shuffled) for the footprints in the layout excerpt that follows; sources: Cadence DE-HDL packaged netlist, KiCad conversion of Wiwynn_Tioga_Pass_MB.brd

R4G11  RES  7.87K 1.0% CHIP  pkg 0402  page 233 : A = VR_PVPP_GHJ_ISET ; B = AGND_PVPP_GHJ

(kicad_pcb
	(version 20260206)
	(generator "pcbnew")
	(generator_version "10.0")
	(general
		(thickness 1.6)
		(legacy_teardrops no)
	)
	(paper "A4")
	(title_block
		(title "Wiwynn_Tioga_Pass_MB.brd")
		(comment 1 "Tioga Pass / footprints 1310-1310 of 4770")
	)
	(layers
		(0 "F.Cu" signal "TOP")
		(4 "In1.Cu" signal "L2GND")
		(6 "In2.Cu" signal "L3")
		(8 "In3.Cu" signal "L4GND")
		(10 "In4.Cu" signal "L5")
		(12 "In5.Cu" signal "L6GND")
		(14 "In6.Cu" signal "L7VCC")
		(16 "In7.Cu" signal "L8VCC")
		(18 "In8.Cu" signal "L9GND")
		(20 "In9.Cu" signal "L10")
		(22 "In10.Cu" signal "L11GND")
		(24 "In11.Cu" signal "L12")
		(26 "In12.Cu" signal "L13GND")
		(2 "B.Cu" signal "BOTTOM")
		(9 "F.Adhes" user "F.Adhesive")
		(11 "B.Adhes" user "B.Adhesive")
		(13 "F.Paste" user "Package Geometry/Pastemask Top")
		(15 "B.Paste" user "Package Geometry/Pastemask Bottom")
		(5 "F.SilkS" user "Ref Des/Silkscreen Top")
		(7 "B.SilkS" user "Ref Des/Silkscreen Bottom")
		(1 "F.Mask" user "Board Geometry/Soldermask Top")
		(3 "B.Mask" user "Board Geometry/Soldermask Bottom")
		(17 "Dwgs.User" user "User.Drawings")
		(19 "Cmts.User" user "User.Comments")
		(21 "Eco1.User" user "User.Eco1")
		(23 "Eco2.User" user "User.Eco2")
		(25 "Edge.Cuts" user "Board Geometry/Outline")
		(27 "Margin" user)
		(31 "F.CrtYd" user "Package Geometry/Place Bound Top")
		(29 "B.CrtYd" user "Package Geometry/Place Bound Bottom")
		(35 "F.Fab" user "Ref Des/Assembly Top")
		(33 "B.Fab" user "Ref Des/Assembly Bottom")
	)
	(footprint ""
		(layer "F.Cu")
		(at 177.927 -8.255)
		(property "Reference" "R4G11"
			(at 0 0 0)
			(layer "F.SilkS")
			(hide yes)
			(effects
				(font
					(size 1.27 1.27)
				)
			)
		)
		(property "Value" ""
			(at 0 0 0)
			(layer "F.Fab")
			(effects
				(font
					(size 1.27 1.27)
				)
			)
		)
		(duplicate_pad_numbers_are_jumpers no)
		(fp_rect
			(start -0.2794 0.9906)
			(end 0.2794 -0.1016)
			(stroke
				(width 0)
				(type default)
			)
			(fill no)
			(layer "F.CrtYd")
		)
		(fp_line
			(start -0.2794 -0.1016)
			(end -0.2794 0.9906)
			(stroke
				(width 0.1)
				(type default)
			)
			(layer "F.Fab")
		)
		(fp_line
			(start -0.2794 0.9906)
			(end 0.2794 0.9906)
			(stroke
				(width 0.1)
				(type default)
			)
			(layer "F.Fab")
		)
		(fp_line
			(start 0.2794 -0.1016)
			(end -0.2794 -0.1016)
			(stroke
				(width 0.1)
				(type default)
			)
			(layer "F.Fab")
		)
		(fp_line
			(start 0.2794 0.9906)
			(end 0.2794 -0.1016)
			(stroke
				(width 0.1)
				(type default)
			)
			(layer "F.Fab")
		)
		(pad "1" smd rect
			(at 0 0)
			(size 0.508 0.508)
			(layers "F.Cu" "F.Mask" "F.Paste")
			(net "VR_PVPP_GHJ_ISET")
		)
		(pad "2" smd rect
			(at 0 0.889)
			(size 0.508 0.508)
			(layers "F.Cu" "F.Mask" "F.Paste")
			(net "AGND_PVPP_GHJ")
		)
		(zone
			(layer "F.Cu")
			(hatch none 0.5)
			(connect_pads
				(clearance 0)
			)
			(min_thickness 0.25)
			(keepout
				(tracks allowed)
				(vias not_allowed)
				(pads allowed)
				(copperpour not_allowed)
				(footprints allowed)
			)
			(placement
				(enabled no)
				(sheetname "")
			)
			(fill
				(thermal_gap 0.5)
				(thermal_bridge_width 0.5)
				(island_removal_mode 0)
			)
			(polygon
				(pts
					(xy 177.673 -7.62) (xy 178.181 -7.62) (xy 178.181 -8.001) (xy 177.673 -8.001)
				)
			)
		)
		(zone
			(layer "F.Cu")
			(hatch none 0.5)
			(connect_pads
				(clearance 0)
			)
			(min_thickness 0.25)
			(keepout
				(tracks not_allowed)
				(vias allowed)
				(pads allowed)
				(copperpour not_allowed)
				(footprints allowed)
			)
			(placement
				(enabled no)
				(sheetname "")
			)
			(fill
				(thermal_gap 0.5)
				(thermal_bridge_width 0.5)
				(island_removal_mode 0)
			)
			(polygon
				(pts
					(xy 177.673 -7.62) (xy 178.181 -7.62) (xy 178.181 -8.001) (xy 177.673 -8.001)
				)
			)
		)
	)
)
